(kicad_pcb
	(version 20260206)
	(generator "pcbnew")
	(generator_version "10.0")
	(general
		(thickness 1.6)
		(legacy_teardrops no)
	)
	(paper "A4")
	(title_block
		(title "timecard-production-celestica-r4006 — R4006-B0001-02_R01.brd")
		(comment 1 "Time Appliance Project (Time Card) / footprints 897-899 of 1113")
	)
	(layers
		(0 "F.Cu" signal "TOP")
		(4 "In1.Cu" signal "L02_GND1")
		(6 "In2.Cu" signal "L03_SIG1")
		(8 "In3.Cu" signal "L04_GND2")
		(10 "In4.Cu" signal "L05_VCC1")
		(12 "In5.Cu" signal "L06_VCC2")
		(14 "In6.Cu" signal "L07_GND3")
		(16 "In7.Cu" signal "L08_SIG2")
		(18 "In8.Cu" signal "L09_GND4")
		(2 "B.Cu" signal "BOTTOM")
		(9 "F.Adhes" user "F.Adhesive")
		(11 "B.Adhes" user "B.Adhesive")
		(13 "F.Paste" user "Package Geometry/Pastemask Top")
		(15 "B.Paste" user "Package Geometry/Pastemask Bottom")
		(5 "F.SilkS" user "Ref Des/Silkscreen Top")
		(7 "B.SilkS" user "Ref Des/Silkscreen Bottom")
		(1 "F.Mask" user "Board Geometry/Soldermask Top")
		(3 "B.Mask" user "Board Geometry/Soldermask Bottom")
		(17 "Dwgs.User" user "User.Drawings")
		(19 "Cmts.User" user "User.Comments")
		(21 "Eco1.User" user "User.Eco1")
		(23 "Eco2.User" user "User.Eco2")
		(25 "Edge.Cuts" user "Board Geometry/Outline")
		(27 "Margin" user)
		(31 "F.CrtYd" user "Package Geometry/Place Bound Top")
		(29 "B.CrtYd" user "Package Geometry/Place Bound Bottom")
		(35 "F.Fab" user "Ref Des/Assembly Top")
		(33 "B.Fab" user "Ref Des/Assembly Bottom")
	)
	(footprint ""
		(layer "B.Cu")
		(at 21.0566 -39.3446)
		(property "Reference" "R148"
			(at -0.3556 4.71297 0)
			(unlocked yes)
			(layer "B.SilkS")
			(effects
				(font
					(size 0.7874 0.5842)
					(thickness 0.1524)
				)
				(justify mirror)
			)
		)
		(property "Value" "VAL*"
			(at -0.02032 2.13233 0)
			(unlocked yes)
			(layer "B.Fab")
			(hide yes)
			(effects
				(font
					(size 0.7874 0.5842)
					(thickness 0.1524)
				)
				(justify mirror)
			)
		)
		(property "Device Type" "RESISTOR-G155-11002-01,10KOHM,A"
			(at -0.008382 1.210564 0)
			(unlocked yes)
			(layer "B.Fab")
			(hide yes)
			(effects
				(font
					(size 0.7874 0.5842)
					(thickness 0.1524)
				)
				(justify mirror)
			)
		)
		(property "User Part Number" "PARTNUM*"
			(at -0.02032 4.024884 0)
			(unlocked yes)
			(layer "Cmts.User")
			(hide yes)
			(effects
				(font
					(size 0.7874 0.5842)
					(thickness 0.1524)
				)
				(justify mirror)
			)
		)
		(property "Tolerance" "TOL*"
			(at -0.044704 3.05435 0)
			(unlocked yes)
			(layer "Cmts.User")
			(hide yes)
			(effects
				(font
					(size 0.7874 0.5842)
					(thickness 0.1524)
				)
				(justify mirror)
			)
		)
		(duplicate_pad_numbers_are_jumpers no)
		(fp_line
			(start -1.143 -0.5588)
			(end 1.143 -0.5588)
			(stroke
				(width 0.1)
				(type default)
			)
			(layer "B.SilkS")
		)
		(fp_line
			(start -1.143 0.5588)
			(end -1.143 -0.5588)
			(stroke
				(width 0.1)
				(type default)
			)
			(layer "B.SilkS")
		)
		(fp_line
			(start 1.143 -0.5588)
			(end 1.143 0.5588)
			(stroke
				(width 0.1)
				(type default)
			)
			(layer "B.SilkS")
		)
		(fp_line
			(start 1.143 0.5588)
			(end -1.143 0.5588)
			(stroke
				(width 0.1)
				(type default)
			)
			(layer "B.SilkS")
		)
		(fp_rect
			(start 1.143 0.5588)
			(end -1.143 -0.5588)
			(stroke
				(width 0)
				(type default)
			)
			(fill no)
			(layer "B.CrtYd")
		)
		(fp_line
			(start -0.508 -0.3048)
			(end 0.508 -0.3048)
			(stroke
				(width 0.1)
				(type default)
			)
			(layer "B.Fab")
		)
		(fp_line
			(start -0.508 0.3048)
			(end -0.508 -0.3048)
			(stroke
				(width 0.1)
				(type default)
			)
			(layer "B.Fab")
		)
		(fp_line
			(start 0.508 -0.3048)
			(end 0.508 0.3048)
			(stroke
				(width 0.1)
				(type default)
			)
			(layer "B.Fab")
		)
		(fp_line
			(start 0.508 0.3048)
			(end -0.508 0.3048)
			(stroke
				(width 0.1)
				(type default)
			)
			(layer "B.Fab")
		)
		(pad "1" smd rect
			(at 0.5334 0 180)
			(size 0.7112 0.6096)
			(layers "B.Cu" "B.Mask" "B.Paste")
			(net "XP3R3V_FPGA")
		)
		(pad "2" smd rect
			(at -0.5334 0 180)
			(size 0.7112 0.6096)
			(layers "B.Cu" "B.Mask" "B.Paste")
			(net "R_PCA9546_I2C_SCL")
		)
		(zone
			(layer "B.Cu")
			(hatch none 0.5)
			(connect_pads
				(clearance 0)
			)
			(min_thickness 0.25)
			(keepout
				(tracks allowed)
				(vias not_allowed)
				(pads allowed)
				(copperpour not_allowed)
				(footprints allowed)
			)
			(placement
				(enabled no)
				(sheetname "")
			)
			(fill
				(thermal_gap 0.5)
				(thermal_bridge_width 0.5)
				(island_removal_mode 0)
			)
			(polygon
				(pts
					(xy 21.1328 -39.0398) (xy 21.1328 -39.6494) (xy 20.9804 -39.6494) (xy 20.9804 -39.0398)
				)
			)
		)
	)
	(footprint ""
		(layer "B.Cu")
		(at 68.326 -57.15 -90)
		(property "Reference" "U12"
			(at 3.97637 -1.143 0)
			(unlocked yes)
			(layer "B.SilkS")
			(effects
				(font
					(size 0.7874 0.5842)
					(thickness 0.1524)
				)
				(justify mirror)
			)
		)
		(property "Value" ""
			(at 0 0 90)
			(layer "B.Fab")
			(effects
				(font
					(size 1.27 1.27)
				)
				(justify mirror)
			)
		)
		(property "Device Type" "TPS2051BDBVT_SOT23_5-G220-1033A"
			(at -0.0508 2.549906 270)
			(unlocked yes)
			(layer "B.Fab")
			(hide yes)
			(effects
				(font
					(size 0.7874 0.5842)
					(thickness 0.1524)
				)
				(justify mirror)
			)
		)
		(property "User Part Number" "PARTNUM*"
			(at -0.0508 3.515106 270)
			(unlocked yes)
			(layer "Cmts.User")
			(hide yes)
			(effects
				(font
					(size 0.7874 0.5842)
					(thickness 0.1524)
				)
				(justify mirror)
			)
		)
		(duplicate_pad_numbers_are_jumpers no)
		(fp_line
			(start -1.0541 1.704086)
			(end 1.0541 1.704086)
			(stroke
				(width 0.1)
				(type default)
			)
			(layer "B.SilkS")
		)
		(fp_line
			(start 1.0541 1.704086)
			(end 1.0541 1.45796)
			(stroke
				(width 0.1)
				(type default)
			)
			(layer "B.SilkS")
		)
		(fp_line
			(start -2.286 1.45796)
			(end -1.0541 1.45796)
			(stroke
				(width 0.1)
				(type default)
			)
			(layer "B.SilkS")
		)
		(fp_line
			(start -1.0541 1.45796)
			(end -1.0541 1.704086)
			(stroke
				(width 0.1)
				(type default)
			)
			(layer "B.SilkS")
		)
		(fp_line
			(start 1.0541 1.45796)
			(end 2.286 1.45796)
			(stroke
				(width 0.1)
				(type default)
			)
			(layer "B.SilkS")
		)
		(fp_line
			(start 2.286 1.45796)
			(end 2.286 -1.45796)
			(stroke
				(width 0.1)
				(type default)
			)
			(layer "B.SilkS")
		)
		(fp_line
			(start -2.286 0.44196)
			(end -2.286 1.45796)
			(stroke
				(width 0.1)
				(type default)
			)
			(layer "B.SilkS")
		)
		(fp_line
			(start -1.0541 0.44196)
			(end -2.286 0.44196)
			(stroke
				(width 0.1)
				(type default)
			)
			(layer "B.SilkS")
		)
		(fp_line
			(start -2.286 -0.44196)
			(end -1.0541 -0.44196)
			(stroke
				(width 0.1)
				(type default)
			)
			(layer "B.SilkS")
		)
		(fp_line
			(start -1.0541 -0.44196)
			(end -1.0541 0.44196)
			(stroke
				(width 0.1)
				(type default)
			)
			(layer "B.SilkS")
		)
		(fp_line
			(start -2.286 -1.45796)
			(end -2.286 -0.44196)
			(stroke
				(width 0.1)
				(type default)
			)
			(layer "B.SilkS")
		)
		(fp_line
			(start -1.0541 -1.45796)
			(end -2.286 -1.45796)
			(stroke
				(width 0.1)
				(type default)
			)
			(layer "B.SilkS")
		)
		(fp_line
			(start 1.0541 -1.45796)
			(end 1.0541 -1.704086)
			(stroke
				(width 0.1)
				(type default)
			)
			(layer "B.SilkS")
		)
		(fp_line
			(start 2.286 -1.45796)
			(end 1.0541 -1.45796)
			(stroke
				(width 0.1)
				(type default)
			)
			(layer "B.SilkS")
		)
		(fp_line
			(start -1.0541 -1.704086)
			(end -1.0541 -1.45796)
			(stroke
				(width 0.1)
				(type default)
			)
			(layer "B.SilkS")
		)
		(fp_line
			(start 1.0541 -1.704086)
			(end -1.0541 -1.704086)
			(stroke
				(width 0.1)
				(type default)
			)
			(layer "B.SilkS")
		)
		(fp_poly
			(pts
				(arc
					(start 2.8956 -1.5494)
					(mid 2.8956 -0.7874)
					(end 2.8956 -1.5494)
				)
			)
			(stroke
				(width 0)
				(type default)
			)
			(fill yes)
			(layer "B.SilkS")
		)
		(fp_rect
			(start 2.54 -1.9558)
			(end -2.54 1.9558)
			(stroke
				(width 0)
				(type default)
			)
			(fill no)
			(layer "B.CrtYd")
		)
		(fp_line
			(start -0.8001 1.450086)
			(end -0.599948 1.249934)
			(stroke
				(width 0.1)
				(type default)
			)
			(layer "B.Fab")
		)
		(fp_line
			(start -0.8001 1.450086)
			(end -0.8001 1.199896)
			(stroke
				(width 0.1)
				(type default)
			)
			(layer "B.Fab")
		)
		(fp_line
			(start 0.8001 1.450086)
			(end -0.8001 1.450086)
			(stroke
				(width 0.1)
				(type default)
			)
			(layer "B.Fab")
		)
		(fp_line
			(start 0.8001 1.450086)
			(end 0.599948 1.249934)
			(stroke
				(width 0.1)
				(type default)
			)
			(layer "B.Fab")
		)
		(fp_line
			(start -0.599948 1.249934)
			(end 0.599948 1.249934)
			(stroke
				(width 0.1)
				(type default)
			)
			(layer "B.Fab")
		)
		(fp_line
			(start 0.599948 1.249934)
			(end 0.599948 -1.249934)
			(stroke
				(width 0.1)
				(type default)
			)
			(layer "B.Fab")
		)
		(fp_line
			(start -1.500124 1.199896)
			(end -0.700024 1.199896)
			(stroke
				(width 0.1)
				(type default)
			)
			(layer "B.Fab")
		)
		(fp_line
			(start -0.700024 1.199896)
			(end -0.700024 0.700024)
			(stroke
				(width 0.1)
				(type default)
			)
			(layer "B.Fab")
		)
		(fp_line
			(start 0.700024 1.199896)
			(end 1.500124 1.199896)
			(stroke
				(width 0.1)
				(type default)
			)
			(layer "B.Fab")
		)
		(fp_line
			(start 0.8001 1.199896)
			(end 0.8001 1.450086)
			(stroke
				(width 0.1)
				(type default)
			)
			(layer "B.Fab")
		)
		(fp_line
			(start 1.500124 1.199896)
			(end 1.500124 0.700024)
			(stroke
				(width 0.1)
				(type default)
			)
			(layer "B.Fab")
		)
		(fp_line
			(start -1.500124 0.700024)
			(end -1.500124 1.199896)
			(stroke
				(width 0.1)
				(type default)
			)
			(layer "B.Fab")
		)
		(fp_line
			(start -0.700024 0.700024)
			(end -1.500124 0.700024)
			(stroke
				(width 0.1)
				(type default)
			)
			(layer "B.Fab")
		)
		(fp_line
			(start 0.700024 0.700024)
			(end 0.700024 1.199896)
			(stroke
				(width 0.1)
				(type default)
			)
			(layer "B.Fab")
		)
		(fp_line
			(start 1.500124 0.700024)
			(end 0.700024 0.700024)
			(stroke
				(width 0.1)
				(type default)
			)
			(layer "B.Fab")
		)
		(fp_line
			(start 0.700024 0.249936)
			(end 1.500124 0.249936)
			(stroke
				(width 0.1)
				(type default)
			)
			(layer "B.Fab")
		)
		(fp_line
			(start 0.8001 0.249936)
			(end 0.8001 0.700024)
			(stroke
				(width 0.1)
				(type default)
			)
			(layer "B.Fab")
		)
		(fp_line
			(start 1.500124 0.249936)
			(end 1.500124 -0.249936)
			(stroke
				(width 0.1)
				(type default)
			)
			(layer "B.Fab")
		)
		(fp_line
			(start 0.700024 -0.249936)
			(end 0.700024 0.249936)
			(stroke
				(width 0.1)
				(type default)
			)
			(layer "B.Fab")
		)
		(fp_line
			(start 1.500124 -0.249936)
			(end 0.700024 -0.249936)
			(stroke
				(width 0.1)
				(type default)
			)
			(layer "B.Fab")
		)
		(fp_line
			(start -1.500124 -0.700024)
			(end -0.700024 -0.700024)
			(stroke
				(width 0.1)
				(type default)
			)
			(layer "B.Fab")
		)
		(fp_line
			(start -0.8001 -0.700024)
			(end -0.8001 0.700024)
			(stroke
				(width 0.1)
				(type default)
			)
			(layer "B.Fab")
		)
		(fp_line
			(start -0.700024 -0.700024)
			(end -0.700024 -1.199896)
			(stroke
				(width 0.1)
				(type default)
			)
			(layer "B.Fab")
		)
		(fp_line
			(start 0.700024 -0.700024)
			(end 1.500124 -0.700024)
			(stroke
				(width 0.1)
				(type default)
			)
			(layer "B.Fab")
		)
		(fp_line
			(start 0.8001 -0.700024)
			(end 0.8001 -0.249936)
			(stroke
				(width 0.1)
				(type default)
			)
			(layer "B.Fab")
		)
		(fp_line
			(start 1.500124 -0.700024)
			(end 1.500124 -1.199896)
			(stroke
				(width 0.1)
				(type default)
			)
			(layer "B.Fab")
		)
		(fp_line
			(start -1.500124 -1.199896)
			(end -1.500124 -0.700024)
			(stroke
				(width 0.1)
				(type default)
			)
			(layer "B.Fab")
		)
		(fp_line
			(start -0.700024 -1.199896)
			(end -1.500124 -1.199896)
			(stroke
				(width 0.1)
				(type default)
			)
			(layer "B.Fab")
		)
		(fp_line
			(start 0.700024 -1.199896)
			(end 0.700024 -0.700024)
			(stroke
				(width 0.1)
				(type default)
			)
			(layer "B.Fab")
		)
		(fp_line
			(start 0.8001 -1.199896)
			(end 0.8001 -1.450086)
			(stroke
				(width 0.1)
				(type default)
			)
			(layer "B.Fab")
		)
		(fp_line
			(start 1.500124 -1.199896)
			(end 0.700024 -1.199896)
			(stroke
				(width 0.1)
				(type default)
			)
			(layer "B.Fab")
		)
		(fp_line
			(start -0.599948 -1.249934)
			(end -0.599948 1.249934)
			(stroke
				(width 0.1)
				(type default)
			)
			(layer "B.Fab")
		)
		(fp_line
			(start -0.599948 -1.249934)
			(end -0.8001 -1.450086)
			(stroke
				(width 0.1)
				(type default)
			)
			(layer "B.Fab")
		)
		(fp_line
			(start 0.599948 -1.249934)
			(end -0.599948 -1.249934)
			(stroke
				(width 0.1)
				(type default)
			)
			(layer "B.Fab")
		)
		(fp_line
			(start 0.599948 -1.249934)
			(end 0.8001 -1.450086)
			(stroke
				(width 0.1)
				(type default)
			)
			(layer "B.Fab")
		)
		(fp_line
			(start -0.8001 -1.450086)
			(end -0.8001 -1.199896)
			(stroke
				(width 0.1)
				(type default)
			)
			(layer "B.Fab")
		)
		(fp_line
			(start 0.8001 -1.450086)
			(end -0.8001 -1.450086)
			(stroke
				(width 0.1)
				(type default)
			)
			(layer "B.Fab")
		)
		(fp_poly
			(pts
				(arc
					(start 0.350012 -1.09982)
					(mid 0.350012 -0.8001)
					(end 0.350012 -1.09982)
				)
			)
			(stroke
				(width 0)
				(type default)
			)
			(fill yes)
			(layer "B.Fab")
		)
		(fp_text user "4"
			(at -2.286 2.44475 270)
			(unlocked yes)
			(layer "B.SilkS")
			(effects
				(font
					(size 0.635 0.4064)
					(thickness 0.1524)
				)
				(justify mirror)
			)
		)
		(fp_text user "3"
			(at 3.58775 1.651 0)
			(unlocked yes)
			(layer "B.SilkS")
			(effects
				(font
					(size 0.635 0.4064)
					(thickness 0.1524)
				)
				(justify mirror)
			)
		)
		(fp_text user "5"
			(at -2.88925 -1.524 0)
			(unlocked yes)
			(layer "B.SilkS")
			(effects
				(font
					(size 0.635 0.4064)
					(thickness 0.1524)
				)
				(justify mirror)
			)
		)
		(fp_text user "3"
			(at 2.794 0.91567 270)
			(unlocked yes)
			(layer "B.Fab")
			(effects
				(font
					(size 0.7874 0.5842)
					(thickness 0.1524)
				)
				(justify mirror)
			)
		)
		(fp_text user "4"
			(at -2.13233 0.762 0)
			(unlocked yes)
			(layer "B.Fab")
			(effects
				(font
					(size 0.7874 0.5842)
					(thickness 0.1524)
				)
				(justify mirror)
			)
		)
		(fp_text user "5"
			(at -2.13233 -1.143 0)
			(unlocked yes)
			(layer "B.Fab")
			(effects
				(font
					(size 0.7874 0.5842)
					(thickness 0.1524)
				)
				(justify mirror)
			)
		)
		(pad "1" smd rect
			(at 1.4351 -0.94996)
			(size 0.508 1.1938)
			(layers "B.Cu" "B.Mask" "B.Paste")
			(net "XP5R0V_MAC_USB")
		)
		(pad "2" smd rect
			(at 1.4351 0)
			(size 0.508 1.1938)
			(layers "B.Cu" "B.Mask" "B.Paste")
			(net "SG")
		)
		(pad "3" smd rect
			(at 1.4351 0.94996)
			(size 0.508 1.1938)
			(layers "B.Cu" "B.Mask" "B.Paste")
			(net "UNNAMED_527_RESISTOR_I206_1")
		)
		(pad "4" smd rect
			(at -1.4351 0.94996)
			(size 0.508 1.1938)
			(layers "B.Cu" "B.Mask" "B.Paste")
			(net "USB_PWR_EN")
		)
		(pad "5" smd rect
			(at -1.4351 -0.94996)
			(size 0.508 1.1938)
			(layers "B.Cu" "B.Mask" "B.Paste")
			(net "XP5R0V_MAC")
		)
	)
	(footprint ""
		(layer "B.Cu")
		(at 151.613108 -49.01311 90)
		(property "Reference" "R69"
			(at 3.81889 -1.030478 270)
			(unlocked yes)
			(layer "B.SilkS")
			(effects
				(font
					(size 0.7874 0.5842)
					(thickness 0.1524)
				)
				(justify mirror)
			)
		)
		(property "Value" "VAL*"
			(at -0.02032 2.13233 90)
			(unlocked yes)
			(layer "B.Fab")
			(hide yes)
			(effects
				(font
					(size 0.7874 0.5842)
					(thickness 0.1524)
				)
				(justify mirror)
			)
		)
		(property "Device Type" "RESISTOR-G155-11001-01,1KOHM,1%"
			(at -0.008382 1.210564 90)
			(unlocked yes)
			(layer "B.Fab")
			(hide yes)
			(effects
				(font
					(size 0.7874 0.5842)
					(thickness 0.1524)
				)
				(justify mirror)
			)
		)
		(property "User Part Number" "PARTNUM*"
			(at -0.02032 4.024884 90)
			(unlocked yes)
			(layer "Cmts.User")
			(hide yes)
			(effects
				(font
					(size 0.7874 0.5842)
					(thickness 0.1524)
				)
				(justify mirror)
			)
		)
		(property "Tolerance" "TOL*"
			(at -0.044704 3.05435 90)
			(unlocked yes)
			(layer "Cmts.User")
			(hide yes)
			(effects
				(font
					(size 0.7874 0.5842)
					(thickness 0.1524)
				)
				(justify mirror)
			)
		)
		(duplicate_pad_numbers_are_jumpers no)
		(fp_line
			(start 1.143 -0.5588)
			(end 1.143 0.5588)
			(stroke
				(width 0.1)
				(type default)
			)
			(layer "B.SilkS")
		)
		(fp_line
			(start -1.143 -0.5588)
			(end 1.143 -0.5588)
			(stroke
				(width 0.1)
				(type default)
			)
			(layer "B.SilkS")
		)
		(fp_line
			(start 1.143 0.5588)
			(end -1.143 0.5588)
			(stroke
				(width 0.1)
				(type default)
			)
			(layer "B.SilkS")
		)
		(fp_line
			(start -1.143 0.5588)
			(end -1.143 -0.5588)
			(stroke
				(width 0.1)
				(type default)
			)
			(layer "B.SilkS")
		)
		(fp_rect
			(start 1.143 0.5588)
			(end -1.143 -0.5588)
			(stroke
				(width 0)
				(type default)
			)
			(fill no)
			(layer "B.CrtYd")
		)
		(fp_line
			(start 0.508 -0.3048)
			(end 0.508 0.3048)
			(stroke
				(width 0.1)
				(type default)
			)
			(layer "B.Fab")
		)
		(fp_line
			(start -0.508 -0.3048)
			(end 0.508 -0.3048)
			(stroke
				(width 0.1)
				(type default)
			)
			(layer "B.Fab")
		)
		(fp_line
			(start 0.508 0.3048)
			(end -0.508 0.3048)
			(stroke
				(width 0.1)
				(type default)
			)
			(layer "B.Fab")
		)
		(fp_line
			(start -0.508 0.3048)
			(end -0.508 -0.3048)
			(stroke
				(width 0.1)
				(type default)
			)
			(layer "B.Fab")
		)
		(pad "1" smd rect
			(at 0.5334 0 270)
			(size 0.7112 0.6096)
			(layers "B.Cu" "B.Mask" "B.Paste")
			(net "SHT3X_ADDR")
		)
		(pad "2" smd rect
			(at -0.5334 0 270)
			(size 0.7112 0.6096)
			(layers "B.Cu" "B.Mask" "B.Paste")
			(net "SG")
		)
		(zone
			(layer "B.Cu")
			(hatch none 0.5)
			(connect_pads
				(clearance 0)
			)
			(min_thickness 0.25)
			(keepout
				(tracks allowed)
				(vias not_allowed)
				(pads allowed)
				(copperpour not_allowed)
				(footprints allowed)
			)
			(placement
				(enabled no)
				(sheetname "")
			)
			(fill
				(thermal_gap 0.5)
				(thermal_bridge_width 0.5)
				(island_removal_mode 0)
			)
			(polygon
				(pts
					(xy 151.917908 -49.08931) (xy 151.308308 -49.08931) (xy 151.308308 -48.93691) (xy 151.917908 -48.93691)
				)
			)
		)
	)
)
